(kicad_pcb
	(version 20260206)
	(generator "pcbnew")
	(generator_version "10.0")
	(general
		(thickness 1.6)
		(legacy_teardrops no)
	)
	(paper "A4")
	(title_block
		(title "04192023_DAF0TMB3IC0_F0TG_MB_C_brd_V02_OCP.brd")
		(comment 1 "Grand Teton / footprint 3444 of 8354 (U6001), pads 1-69 of 69")
	)
	(layers
		(0 "F.Cu" signal "TOP")
		(4 "In1.Cu" signal "GND")
		(6 "In2.Cu" signal "IN1")
		(8 "In3.Cu" signal "GND1")
		(10 "In4.Cu" signal "IN2")
		(12 "In5.Cu" signal "GND2")
		(14 "In6.Cu" signal "IN3")
		(16 "In7.Cu" signal "GND3")
		(18 "In8.Cu" signal "VCC")
		(20 "In9.Cu" signal "VCC1")
		(22 "In10.Cu" signal "GND4")
		(24 "In11.Cu" signal "IN4")
		(26 "In12.Cu" signal "GND5")
		(28 "In13.Cu" signal "IN5")
		(30 "In14.Cu" signal "GND6")
		(32 "In15.Cu" signal "IN6")
		(34 "In16.Cu" signal "GND7")
		(2 "B.Cu" signal "BOTTOM")
		(9 "F.Adhes" user "F.Adhesive")
		(11 "B.Adhes" user "B.Adhesive")
		(13 "F.Paste" user "Package Geometry/Pastemask Top")
		(15 "B.Paste" user "Package Geometry/Pastemask Bottom")
		(5 "F.SilkS" user "Ref Des/Silkscreen Top")
		(7 "B.SilkS" user "Ref Des/Silkscreen Bottom")
		(1 "F.Mask" user "Board Geometry/Soldermask Top")
		(3 "B.Mask" user "Board Geometry/Soldermask Bottom")
		(17 "Dwgs.User" user "User.Drawings")
		(19 "Cmts.User" user "User.Comments")
		(21 "Eco1.User" user "User.Eco1")
		(23 "Eco2.User" user "User.Eco2")
		(25 "Edge.Cuts" user "Board Geometry/Outline")
		(27 "Margin" user)
		(31 "F.CrtYd" user "Package Geometry/Place Bound Top")
		(29 "B.CrtYd" user "Package Geometry/Place Bound Bottom")
		(35 "F.Fab" user "Ref Des/Assembly Top")
		(33 "B.Fab" user "Ref Des/Assembly Bottom")
	)
	(footprint ""
		(layer "F.Cu")
		(at 132.694172 -36.873434 180)
		(property "Reference" "U6001"
			(at -4.192016 6.04266 0)
			(unlocked yes)
			(layer "F.SilkS")
			(effects
				(font
					(size 0.7874 0.5842)
					(thickness 0.1524)
				)
				(justify left)
			)
		)
		(property "Value" ""
			(at 0 0 180)
			(layer "F.Fab")
			(effects
				(font
					(size 1.27 1.27)
				)
			)
		)
		(duplicate_pad_numbers_are_jumpers no)
		(pad "1" smd rect
			(at -3.999992 -3.199892 270)
			(size 0.1778 1.016)
			(layers "F.Cu" "F.Mask" "F.Paste")
			(net "P1V2_CPU0_USB_DVDD12")
		)
		(pad "2" smd rect
			(at -3.849878 -2.800096 270)
			(size 0.1778 1.3208)
			(layers "F.Cu" "F.Mask" "F.Paste")
			(net "USB_CPU0_HUB1_RREF_USB2")
		)
		(pad "3" smd rect
			(at -3.849878 -2.400046 270)
			(size 0.1778 1.3208)
			(layers "F.Cu" "F.Mask" "F.Paste")
			(net "P1V2_CPU0_USB_DVDD12")
		)
		(pad "4" smd rect
			(at -3.849878 -1.999996 270)
			(size 0.1778 1.3208)
			(layers "F.Cu" "F.Mask" "F.Paste")
			(net "P3V3_AUX_CPU0_USB_AVDD33")
		)
		(pad "5" smd rect
			(at -3.849878 -1.599946 270)
			(size 0.1778 1.3208)
			(layers "F.Cu" "F.Mask" "F.Paste")
			(net "USB3_CPU0_BMC_RX_HUB1_DN")
		)
		(pad "6" smd rect
			(at -3.849878 -1.199896 270)
			(size 0.1778 1.3208)
			(layers "F.Cu" "F.Mask" "F.Paste")
			(net "USB3_CPU0_BMC_RX_HUB1_DP")
		)
		(pad "7" smd rect
			(at -3.849878 -0.8001 270)
			(size 0.1778 1.3208)
			(layers "F.Cu" "F.Mask" "F.Paste")
			(net "P1V2_AUX")
		)
		(pad "8" smd rect
			(at -3.849878 -0.40005 270)
			(size 0.1778 1.3208)
			(layers "F.Cu" "F.Mask" "F.Paste")
			(net "USB3_CPU0_BMC_TX_C1_DN")
		)
		(pad "9" smd rect
			(at -3.849878 0 270)
			(size 0.1778 1.3208)
			(layers "F.Cu" "F.Mask" "F.Paste")
			(net "USB3_CPU0_BMC_TX_C1_DP")
		)
		(pad "10" smd rect
			(at -3.849878 0.40005 270)
			(size 0.1778 1.3208)
			(layers "F.Cu" "F.Mask" "F.Paste")
			(net "P1V2_AUX")
		)
		(pad "11" smd rect
			(at -3.849878 0.8001 270)
			(size 0.1778 1.3208)
			(layers "F.Cu" "F.Mask" "F.Paste")
			(net "Net_10799")
		)
		(pad "12" smd rect
			(at -3.849878 1.199896 270)
			(size 0.1778 1.3208)
			(layers "F.Cu" "F.Mask" "F.Paste")
			(net "Net_10800")
		)
		(pad "13" smd rect
			(at -3.849878 1.599946 270)
			(size 0.1778 1.3208)
			(layers "F.Cu" "F.Mask" "F.Paste")
			(net "P1V2_AUX")
		)
		(pad "14" smd rect
			(at -3.849878 1.999996 270)
			(size 0.1778 1.3208)
			(layers "F.Cu" "F.Mask" "F.Paste")
			(net "Net_10802")
		)
		(pad "15" smd rect
			(at -3.849878 2.400046 270)
			(size 0.1778 1.3208)
			(layers "F.Cu" "F.Mask" "F.Paste")
			(net "Net_10801")
		)
		(pad "16" smd rect
			(at -3.849878 2.800096 270)
			(size 0.1778 1.3208)
			(layers "F.Cu" "F.Mask" "F.Paste")
			(net "P1V2_AUX")
		)
		(pad "17" smd rect
			(at -3.999992 3.199892 270)
			(size 0.1778 1.016)
			(layers "F.Cu" "F.Mask" "F.Paste")
			(net "USB_CPU0_HUB1_VBUS_US")
		)
		(pad "18" smd rect
			(at -3.199892 3.999992 180)
			(size 0.1778 1.016)
			(layers "F.Cu" "F.Mask" "F.Paste")
			(net "USB_CPU0_HUB1_VBUS_DS")
		)
		(pad "19" smd rect
			(at -2.800096 3.849878 180)
			(size 0.1778 1.3208)
			(layers "F.Cu" "F.Mask" "F.Paste")
			(net "P1V2_CPU0_USB_DVDD12")
		)
		(pad "20" smd rect
			(at -2.400046 3.849878 180)
			(size 0.1778 1.3208)
			(layers "F.Cu" "F.Mask" "F.Paste")
			(net "TP_CPU0_USB_HUB1_SUSPEND")
		)
		(pad "21" smd rect
			(at -1.999996 3.849878 180)
			(size 0.1778 1.3208)
			(layers "F.Cu" "F.Mask" "F.Paste")
			(net "PU_CPU0_USB_HUB_RESERVED1")
		)
		(pad "22" smd rect
			(at -1.599946 3.849878 180)
			(size 0.1778 1.3208)
			(layers "F.Cu" "F.Mask" "F.Paste")
			(net "PU_CPU0_USB_HUB_RESERVED2")
		)
		(pad "23" smd rect
			(at -1.199896 3.849878 180)
			(size 0.1778 1.3208)
			(layers "F.Cu" "F.Mask" "F.Paste")
			(net "USB_CPU0_HUB1_MODE_SEL0")
		)
		(pad "24" smd rect
			(at -0.8001 3.849878 180)
			(size 0.1778 1.3208)
			(layers "F.Cu" "F.Mask" "F.Paste")
			(net "USB_CPU0_HUB1_MODE_SEL1")
		)
		(pad "25" smd rect
			(at -0.40005 3.849878 180)
			(size 0.1778 1.3208)
			(layers "F.Cu" "F.Mask" "F.Paste")
			(net "Net_10798")
		)
		(pad "26" smd rect
			(at 0 3.849878 180)
			(size 0.1778 1.3208)
			(layers "F.Cu" "F.Mask" "F.Paste")
			(net "USB_CPU0_HUB1_RREF_SS")
		)
		(pad "27" smd rect
			(at 0.40005 3.849878 180)
			(size 0.1778 1.3208)
			(layers "F.Cu" "F.Mask" "F.Paste")
			(net "P1V2_CPU0_USB_DVDD12")
		)
		(pad "28" smd rect
			(at 0.8001 3.849878 180)
			(size 0.1778 1.3208)
			(layers "F.Cu" "F.Mask" "F.Paste")
			(net "P3V3_AUX")
		)
		(pad "29" smd rect
			(at 1.199896 3.849878 180)
			(size 0.1778 1.3208)
			(layers "F.Cu" "F.Mask" "F.Paste")
			(net "PU_CPU0_USB_HUB_PWR_EN")
		)
		(pad "30" smd rect
			(at 1.599946 3.849878 180)
			(size 0.1778 1.3208)
			(layers "F.Cu" "F.Mask" "F.Paste")
			(net "PU_CPU0_USB_HUB_OVRCURR")
		)
		(pad "31" smd rect
			(at 1.999996 3.849878 180)
			(size 0.1778 1.3208)
			(layers "F.Cu" "F.Mask" "F.Paste")
			(net "RST_USB_CPU0_HUB1_R_N")
		)
		(pad "32" smd rect
			(at 2.400046 3.849878 180)
			(size 0.1778 1.3208)
			(layers "F.Cu" "F.Mask" "F.Paste")
			(net "SMB_USB_CPU0_HUB1_SCL")
		)
		(pad "33" smd rect
			(at 2.800096 3.849878 180)
			(size 0.1778 1.3208)
			(layers "F.Cu" "F.Mask" "F.Paste")
			(net "SMB_USB_CPU0_HUB1_SDA")
		)
		(pad "34" smd rect
			(at 3.199892 3.999992 180)
			(size 0.1778 1.016)
			(layers "F.Cu" "F.Mask" "F.Paste")
			(net "P1V2_AUX")
		)
		(pad "35" smd rect
			(at 3.999992 3.199892 270)
			(size 0.1778 1.016)
			(layers "F.Cu" "F.Mask" "F.Paste")
			(net "Net_10807")
		)
		(pad "36" smd rect
			(at 3.849878 2.800096 270)
			(size 0.1778 1.3208)
			(layers "F.Cu" "F.Mask" "F.Paste")
			(net "Net_10808")
		)
		(pad "37" smd rect
			(at 3.849878 2.400046 270)
			(size 0.1778 1.3208)
			(layers "F.Cu" "F.Mask" "F.Paste")
			(net "P1V2_AUX")
		)
		(pad "38" smd rect
			(at 3.849878 1.999996 270)
			(size 0.1778 1.3208)
			(layers "F.Cu" "F.Mask" "F.Paste")
			(net "Net_10805")
		)
		(pad "39" smd rect
			(at 3.849878 1.599946 270)
			(size 0.1778 1.3208)
			(layers "F.Cu" "F.Mask" "F.Paste")
			(net "Net_10806")
		)
		(pad "40" smd rect
			(at 3.849878 1.199896 270)
			(size 0.1778 1.3208)
			(layers "F.Cu" "F.Mask" "F.Paste")
			(net "GND")
		)
		(pad "41" smd rect
			(at 3.849878 0.8001 270)
			(size 0.1778 1.3208)
			(layers "F.Cu" "F.Mask" "F.Paste")
			(net "Net_10811")
		)
		(pad "42" smd rect
			(at 3.849878 0.40005 270)
			(size 0.1778 1.3208)
			(layers "F.Cu" "F.Mask" "F.Paste")
			(net "Net_10812")
		)
		(pad "43" smd rect
			(at 3.849878 0 270)
			(size 0.1778 1.3208)
			(layers "F.Cu" "F.Mask" "F.Paste")
			(net "P1V2_AUX")
		)
		(pad "44" smd rect
			(at 3.849878 -0.40005 270)
			(size 0.1778 1.3208)
			(layers "F.Cu" "F.Mask" "F.Paste")
			(net "Net_10814")
		)
		(pad "45" smd rect
			(at 3.849878 -0.8001 270)
			(size 0.1778 1.3208)
			(layers "F.Cu" "F.Mask" "F.Paste")
			(net "Net_10813")
		)
		(pad "46" smd rect
			(at 3.849878 -1.199896 270)
			(size 0.1778 1.3208)
			(layers "F.Cu" "F.Mask" "F.Paste")
			(net "P1V2_AUX")
		)
		(pad "47" smd rect
			(at 3.849878 -1.599946 270)
			(size 0.1778 1.3208)
			(layers "F.Cu" "F.Mask" "F.Paste")
			(net "USB3_CPU0_BMC_HUB1_TX_DP")
		)
		(pad "48" smd rect
			(at 3.849878 -1.999996 270)
			(size 0.1778 1.3208)
			(layers "F.Cu" "F.Mask" "F.Paste")
			(net "USB3_CPU0_BMC_HUB1_TX_DN")
		)
		(pad "49" smd rect
			(at 3.849878 -2.400046 270)
			(size 0.1778 1.3208)
			(layers "F.Cu" "F.Mask" "F.Paste")
			(net "P1V2_AUX")
		)
		(pad "50" smd rect
			(at 3.849878 -2.800096 270)
			(size 0.1778 1.3208)
			(layers "F.Cu" "F.Mask" "F.Paste")
			(net "USB3_CPU0_BMC_RX_C1_DN")
		)
		(pad "51" smd rect
			(at 3.999992 -3.199892 270)
			(size 0.1778 1.016)
			(layers "F.Cu" "F.Mask" "F.Paste")
			(net "USB3_CPU0_BMC_RX_C1_DP")
		)
		(pad "52" smd rect
			(at 3.199892 -3.999992 180)
			(size 0.1778 1.016)
			(layers "F.Cu" "F.Mask" "F.Paste")
			(net "P1V2_AUX")
		)
		(pad "53" smd rect
			(at 2.800096 -3.849878 180)
			(size 0.1778 1.3208)
			(layers "F.Cu" "F.Mask" "F.Paste")
			(net "P1V2_AUX")
		)
		(pad "54" smd rect
			(at 2.400046 -3.849878 180)
			(size 0.1778 1.3208)
			(layers "F.Cu" "F.Mask" "F.Paste")
			(net "XTAL_USB_CPU0_HUB1_XOUT")
		)
		(pad "55" smd rect
			(at 1.999996 -3.849878 180)
			(size 0.1778 1.3208)
			(layers "F.Cu" "F.Mask" "F.Paste")
			(net "XTAL_USB_CPU0_HUB1_XIN")
		)
		(pad "56" smd rect
			(at 1.599946 -3.849878 180)
			(size 0.1778 1.3208)
			(layers "F.Cu" "F.Mask" "F.Paste")
			(net "P3V3_AUX")
		)
		(pad "57" smd rect
			(at 1.199896 -3.849878 180)
			(size 0.1778 1.3208)
			(layers "F.Cu" "F.Mask" "F.Paste")
			(net "USB2_CPU0_P0_R1_DP")
		)
		(pad "58" smd rect
			(at 0.8001 -3.849878 180)
			(size 0.1778 1.3208)
			(layers "F.Cu" "F.Mask" "F.Paste")
			(net "USB2_CPU0_P0_R1_DN")
		)
		(pad "59" smd rect
			(at 0.40005 -3.849878 180)
			(size 0.1778 1.3208)
			(layers "F.Cu" "F.Mask" "F.Paste")
			(net "USB2_CPU0_P0_HUB1_R_DN")
		)
		(pad "60" smd rect
			(at 0 -3.849878 180)
			(size 0.1778 1.3208)
			(layers "F.Cu" "F.Mask" "F.Paste")
			(net "USB2_CPU0_P0_HUB1_R_DP")
		)
		(pad "61" smd rect
			(at -0.40005 -3.849878 180)
			(size 0.1778 1.3208)
			(layers "F.Cu" "F.Mask" "F.Paste")
			(net "P3V3_AUX")
		)
		(pad "62" smd rect
			(at -0.8001 -3.849878 180)
			(size 0.1778 1.3208)
			(layers "F.Cu" "F.Mask" "F.Paste")
			(net "Net_10815")
		)
		(pad "63" smd rect
			(at -1.199896 -3.849878 180)
			(size 0.1778 1.3208)
			(layers "F.Cu" "F.Mask" "F.Paste")
			(net "Net_10816")
		)
		(pad "64" smd rect
			(at -1.599946 -3.849878 180)
			(size 0.1778 1.3208)
			(layers "F.Cu" "F.Mask" "F.Paste")
			(net "Net_10810")
		)
		(pad "65" smd rect
			(at -1.999996 -3.849878 180)
			(size 0.1778 1.3208)
			(layers "F.Cu" "F.Mask" "F.Paste")
			(net "Net_10809")
		)
		(pad "66" smd rect
			(at -2.400046 -3.849878 180)
			(size 0.1778 1.3208)
			(layers "F.Cu" "F.Mask" "F.Paste")
			(net "P3V3_AUX")
		)
		(pad "67" smd rect
			(at -2.800096 -3.849878 180)
			(size 0.1778 1.3208)
			(layers "F.Cu" "F.Mask" "F.Paste")
			(net "Net_10803")
		)
		(pad "68" smd rect
			(at -3.199892 -3.999992 180)
			(size 0.1778 1.016)
			(layers "F.Cu" "F.Mask" "F.Paste")
			(net "Net_10804")
		)
		(pad "TH" smd rect
			(at 0 0 180)
			(size 5.207 5.207)
			(layers "F.Cu" "F.Mask" "F.Paste")
			(net "GND")
		)
	)
)
